FILE_TYPE = CONNECTIVITY;
{Allegro Design Entry HDL 16.6-p007 (v16-6-112F) 10/10/2012}
"PAGE_NUMBER" = 71;
0"NC";
1"PVCCIN_CPU1\g";
2"PVCCIN_CPU1\g";
3"PVCCIN_CPU1\g";
4"PVCCIN_CPU1\g";
5"GND\g";
6"PVCCIN_CPU1\g";
7"PVCCIO_CPU1\g";
8"VSENSE_PMAX_CPU1";
9"VSENSE_PVCCIN_CPU1_SKT_VSEN";
10"VSENSE_PVCCIN_CPU1_SKT_VRTN";
11"VSENSE_VCCINR2PMAX_CPU1";
%"PVCCIN_CPU1"
"1","(-5425,4425)","0","mstr_symbols","I35";
;
HDL_POWER"PVCCIN_CPU1"
BODY_TYPE"PLUMBING"
CDS_LIB"mstr_symbols"
VOLTAGE"2.0V";
"G\NAC"1;
%"PVCCIN_CPU1"
"1","(-7325,4400)","0","mstr_symbols","I36";
;
HDL_POWER"PVCCIN_CPU1"
BODY_TYPE"PLUMBING"
CDS_LIB"mstr_symbols"
VOLTAGE"2.0V";
"G\NAC"2;
%"PVCCIN_CPU1"
"1","(-3600,4400)","0","mstr_symbols","I40";
;
HDL_POWER"PVCCIN_CPU1"
BODY_TYPE"PLUMBING"
CDS_LIB"mstr_symbols"
VOLTAGE"2.0V";
"G\NAC"3;
%"PVCCIN_CPU1"
"1","(-1725,4375)","0","mstr_symbols","I41";
;
HDL_POWER"PVCCIN_CPU1"
CDS_LIB"mstr_symbols"
BODY_TYPE"PLUMBING"
VOLTAGE"2.0V";
"G\NAC"4;
%"GND"
"1","(-500,525)","0","mstr_symbols","I42";
;
HDL_POWER"GND"
CDS_LIB"mstr_symbols"
SIZE"1B"
VOLTAGE"0.0V"
BODY_TYPE"PLUMBING";
"A\NAC"5;
%"RES"
"2","(-500,750)","0","mstr_discrete","I43";
;
CDS_SEC"1"
SEC_TYPE"0402"
BOM_COST"PROC_SOCKET"
SEC"1"
ROOM"CPU1"
CDS_LOCATION"R3D27"
CDS_LIB"mstr_discrete"
PART_NUMBER"G85996-031"
TOLERANCE"0.1%"
VALUE"249"
LOCATION"R3D27"
WATTAGE"1/16W"
MATERIAL"CHIP"
PACK_TYPE"0402";
"A"
$PN"1"8;
"B"
$PN"2"5;
%"PVCCIN_CPU1"
"1","(-1100,1700)","0","mstr_symbols","I45";
;
VOLTAGE"2.0V"
CDS_LIB"mstr_symbols"
BODY_TYPE"PLUMBING"
HDL_POWER"PVCCIN_CPU1";
"G\NAC"6;
%"RES"
"2","(-1100,1400)","0","mstr_discrete","I49";
;
CDS_SEC"1"
BOM_COST"PROC_SOCKET"
SEC_TYPE"0603"
SEC"1"
CDS_LOCATION"RT8P1"
ROOM"CPU1"
CDS_LIB"mstr_discrete"
LOCATION"RT8P1"
PART_NUMBER"G22026-050"
VALUE"100.0K"
TOLERANCE"1%"
PACK_TYPE"0603"
MATERIAL"CHIP"
WATTAGE"1/10W";
"A"
$PN"1"6;
"B"
$PN"2"11;
%"SKX_EXT_B"
"18","(-6375,2525)","0","chpset_lib","I50";
;
CDS_SEC"18"
PACK_TYPE"BGA1"
SEC_TYPE"BGA1"
SEC"18"
CDS_LOCATION"U2D1"
CDS_LIB"chpset_lib"
LOCATION"U2D1"
MATERIAL"IC"
PART_NUMBER"TBD";
"VCCIN<130>"
$PN"BN78"1;
"VCCIN<131>"
$PN"BN76"1;
"VCCIN<132>"
$PN"BN74"1;
"VCCIN<133>"
$PN"BN72"1;
"VCCIN<134>"
$PN"BN70"1;
"VCCIN<135>"
$PN"BN68"1;
"VCCIN<136>"
$PN"BN66"1;
"VCCIN<137>"
$PN"BN64"1;
"VCCIN<138>"
$PN"BN62"1;
"VCCIN<139>"
$PN"BN60"1;
"VCCIN<140>"
$PN"BM83"1;
"VCCIN<141>"
$PN"BM81"1;
"VCCIN<142>"
$PN"BM79"1;
"VCCIN<143>"
$PN"BM77"1;
"VCCIN<144>"
$PN"BM75"1;
"VCCIN<145>"
$PN"BM73"1;
"VCCIN<146>"
$PN"BM71"1;
"VCCIN<147>"
$PN"BM69"1;
"VCCIN<148>"
$PN"BM67"1;
"VCCIN<149>"
$PN"BM65"1;
"VCCIN<150>"
$PN"BM63"1;
"VCCIN<151>"
$PN"BM61"1;
"VCCIN<152>"
$PN"BL84"1;
"VCCIN<153>"
$PN"BL62"1;
"VCCIN<154>"
$PN"BL60"1;
"VCCIN<155>"
$PN"BK83"1;
"VCCIN<156>"
$PN"BK81"1;
"VCCIN<157>"
$PN"BK79"1;
"VCCIN<158>"
$PN"BK77"1;
"VCCIN<159>"
$PN"BK75"1;
"VCCIN<160>"
$PN"BK73"1;
"VCCIN<161>"
$PN"BK71"1;
"VCCIN<162>"
$PN"BK69"1;
"VCCIN<163>"
$PN"BK67"1;
"VCCIN<164>"
$PN"BK65"1;
"VCCIN<165>"
$PN"BK63"1;
"VCCIN<166>"
$PN"BK61"1;
"VCCIN<167>"
$PN"BJ84"1;
"VCCIN<168>"
$PN"BJ82"1;
"VCCIN<169>"
$PN"BJ80"1;
"VCCIN<170>"
$PN"BJ78"1;
"VCCIN<171>"
$PN"BJ76"1;
"VCCIN<172>"
$PN"BJ74"1;
"VCCIN<173>"
$PN"BJ72"1;
"VCCIN<174>"
$PN"BJ70"1;
"VCCIN<175>"
$PN"BJ68"1;
"VCCIN<176>"
$PN"BJ66"1;
"VCCIN<177>"
$PN"BJ64"1;
"VCCIN<178>"
$PN"BJ62"1;
"VCCIN<179>"
$PN"BJ60"1;
"VCCIN<180>"
$PN"BH83"1;
"VCCIN<181>"
$PN"BH81"1;
"VCCIN<182>"
$PN"BH79"1;
"VCCIN<183>"
$PN"BH77"1;
"VCCIN<184>"
$PN"BH75"1;
"VCCIN<185>"
$PN"BH73"1;
"VCCIN<186>"
$PN"BH71"1;
"VCCIN<187>"
$PN"BH69"1;
"VCCIN<188>"
$PN"BH67"1;
"VCCIN<189>"
$PN"BH65"1;
"VCCIN<190>"
$PN"BH63"1;
"VCCIN<191>"
$PN"BH61"1;
"VCCIN<192>"
$PN"BG84"1;
"VCCIN<193>"
$PN"BG70"1;
"VCCIN<194>"
$PN"BG68"1;
"VCCIN<195>"
$PN"BG66"1;
"VCCIN<196>"
$PN"BG64"1;
"VCCIN<197>"
$PN"BG62"1;
"VCCIN<198>"
$PN"BG60"1;
"VCCIN<199>"
$PN"BF85"2;
"VCCIN<200>"
$PN"BF83"2;
"VCCIN<201>"
$PN"BF81"2;
"VCCIN<202>"
$PN"BF79"2;
"VCCIN<203>"
$PN"BF77"2;
"VCCIN<204>"
$PN"BF75"2;
"VCCIN<205>"
$PN"BF73"2;
"VCCIN<206>"
$PN"BF61"2;
"VCCIN<207>"
$PN"BE84"2;
"VCCIN<208>"
$PN"BE82"2;
"VCCIN<209>"
$PN"BE80"2;
"VCCIN<210>"
$PN"BE78"2;
"VCCIN<211>"
$PN"BE76"2;
"VCCIN<212>"
$PN"BE74"2;
"VCCIN<213>"
$PN"BE72"2;
"VCCIN<214>"
$PN"BE62"2;
"VCCIN<215>"
$PN"BE60"2;
"VCCIN<216>"
$PN"BD85"2;
"VCCIN<217>"
$PN"BD83"2;
"VCCIN<218>"
$PN"BD81"2;
"VCCIN<219>"
$PN"BD79"2;
"VCCIN<220>"
$PN"BD77"2;
"VCCIN<221>"
$PN"BD75"2;
"VCCIN<222>"
$PN"BD73"2;
"VCCIN<223>"
$PN"BD61"2;
"VCCIN<224>"
$PN"BC84"2;
"VCCIN<225>"
$PN"BC62"2;
"VCCIN<226>"
$PN"BC60"2;
"VCCIN<227>"
$PN"BB85"2;
"VCCIN<228>"
$PN"BB61"2;
"VCCIN<229>"
$PN"BA60"2;
"VCCIN<230>"
$PN"AY61"2;
"VCCIN<231>"
$PN"AW60"2;
"VCCIN<232>"
$PN"AV61"2;
"VCCIN<233>"
$PN"AV59"2;
"VCCIN<234>"
$PN"AU60"2;
"VCCIN<235>"
$PN"AU58"2;
"VCCIN<236>"
$PN"AT59"2;
"VCCIN<237>"
$PN"AT57"2;
"VCCIN<238>"
$PN"AR58"2;
"VCCIN<239>"
$PN"AR56"2;
"VCCIN<240>"
$PN"AP57"2;
"VCCIN<241>"
$PN"AP55"2;
"VCCIN<242>"
$PN"AN56"2;
"VCCIN<243>"
$PN"AN54"2;
"VCCIN<244>"
$PN"AN32"2;
"VCCIN<245>"
$PN"AM55"2;
"VCCIN<246>"
$PN"AM53"2;
"VCCIN<247>"
$PN"AM33"2;
"VCCIN<248>"
$PN"AL54"2;
"VCCIN<249>"
$PN"AL52"2;
"VCCIN<250>"
$PN"AL50"2;
"VCCIN<251>"
$PN"AL48"2;
"VCCIN<252>"
$PN"AL46"2;
"VCCIN<253>"
$PN"AL34"2;
"VCCIN<254>"
$PN"AK53"2;
"VCCIN<255>"
$PN"AK51"2;
"VCCIN<256>"
$PN"AK49"2;
"VCCIN<257>"
$PN"AK47"2;
"VCCIN<258>"
$PN"AK45"2;
"VCCIN<259>"
$PN"AK35"2;
"VCCIN<260>"
$PN"AJ36"2;
"VCCIN<261>"
$PN"AH41"2;
"VCCIN<262>"
$PN"AH39"2;
"VCCIN<263>"
$PN"AH37"2;
"VCCIN<264>"
$PN"AG42"2;
"VCCIN<265>"
$PN"AG40"2;
"VCCIN<266>"
$PN"AG38"2;
"VCCIN<267>"
$PN"AF43"2;
%"SKX_EXT_B"
"19","(-2675,2525)","0","chpset_lib","I51";
;
CDS_SEC"19"
PACK_TYPE"BGA1"
SEC_TYPE"BGA1"
SEC"19"
CDS_LOCATION"U2D1"
CDS_LIB"chpset_lib"
LOCATION"U2D1"
MATERIAL"IC"
PART_NUMBER"TBD";
"VSS_VCCIN_SENSE"
$PN"AY85"10;
"VSENSEPMAX"
$PN"AD41"8;
"VCCIN_SENSE"
$PN"BA86"9;
"VCCINPMAX<0>"
$PN"AW86"11;
"VCCINPMAX<1>"
$PN"AV85"11;
"VCCIN<0>"
$PN"CY49"4;
"VCCIN<1>"
$PN"CY47"4;
"VCCIN<2>"
$PN"CW50"4;
"VCCIN<3>"
$PN"CW48"4;
"VCCIN<4>"
$PN"CW46"4;
"VCCIN<5>"
$PN"CV51"4;
"VCCIN<6>"
$PN"CU54"4;
"VCCIN<7>"
$PN"CU52"4;
"VCCIN<8>"
$PN"CU42"4;
"VCCIN<9>"
$PN"CU40"4;
"VCCIN<10>"
$PN"CU38"4;
"VCCIN<11>"
$PN"CT55"4;
"VCCIN<12>"
$PN"CT53"4;
"VCCIN<13>"
$PN"CT41"4;
"VCCIN<14>"
$PN"CT39"4;
"VCCIN<15>"
$PN"CT37"4;
"VCCIN<16>"
$PN"CR56"4;
"VCCIN<17>"
$PN"CR54"4;
"VCCIN<18>"
$PN"CR34"4;
"VCCIN<19>"
$PN"CP57"4;
"VCCIN<20>"
$PN"CP55"4;
"VCCIN<21>"
$PN"CP33"4;
"VCCIN<22>"
$PN"CN58"4;
"VCCIN<23>"
$PN"CN56"4;
"VCCIN<24>"
$PN"CM59"4;
"VCCIN<25>"
$PN"CM57"4;
"VCCIN<26>"
$PN"CL60"4;
"VCCIN<27>"
$PN"CL58"4;
"VCCIN<28>"
$PN"CK61"4;
"VCCIN<29>"
$PN"CK59"4;
"VCCIN<30>"
$PN"CJ60"4;
"VCCIN<31>"
$PN"CH85"4;
"VCCIN<32>"
$PN"CH61"4;
"VCCIN<33>"
$PN"CG84"4;
"VCCIN<34>"
$PN"CG60"4;
"VCCIN<35>"
$PN"CF85"4;
"VCCIN<36>"
$PN"CF61"4;
"VCCIN<37>"
$PN"CE84"4;
"VCCIN<38>"
$PN"CE60"4;
"VCCIN<39>"
$PN"CD85"4;
"VCCIN<40>"
$PN"CD83"4;
"VCCIN<41>"
$PN"CD61"4;
"VCCIN<42>"
$PN"CC84"4;
"VCCIN<43>"
$PN"CC62"4;
"VCCIN<44>"
$PN"CC60"4;
"VCCIN<45>"
$PN"CB83"4;
"VCCIN<46>"
$PN"CB81"4;
"VCCIN<47>"
$PN"CB79"4;
"VCCIN<48>"
$PN"CB77"4;
"VCCIN<49>"
$PN"CB75"4;
"VCCIN<50>"
$PN"CB73"4;
"VCCIN<51>"
$PN"CB61"4;
"VCCIN<52>"
$PN"CA84"4;
"VCCIN<53>"
$PN"CA82"4;
"VCCIN<54>"
$PN"CA80"4;
"VCCIN<55>"
$PN"CA78"4;
"VCCIN<56>"
$PN"CA76"4;
"VCCIN<57>"
$PN"CA74"4;
"VCCIN<58>"
$PN"CA72"4;
"VCCIN<59>"
$PN"CA62"4;
"VCCIN<60>"
$PN"CA60"4;
"VCCIN<61>"
$PN"BY83"3;
"VCCIN<62>"
$PN"BY81"3;
"VCCIN<63>"
$PN"BY79"3;
"VCCIN<64>"
$PN"BY77"3;
"VCCIN<65>"
$PN"BY75"3;
"VCCIN<66>"
$PN"BY73"3;
"VCCIN<67>"
$PN"BY61"3;
"VCCIN<68>"
$PN"BW84"3;
"VCCIN<69>"
$PN"BW70"3;
"VCCIN<70>"
$PN"BW68"3;
"VCCIN<71>"
$PN"BW66"3;
"VCCIN<72>"
$PN"BW64"3;
"VCCIN<73>"
$PN"BW62"3;
"VCCIN<74>"
$PN"BW60"3;
"VCCIN<75>"
$PN"BV83"3;
"VCCIN<76>"
$PN"BV81"3;
"VCCIN<77>"
$PN"BV79"3;
"VCCIN<78>"
$PN"BV77"3;
"VCCIN<79>"
$PN"BV75"3;
"VCCIN<80>"
$PN"BV73"3;
"VCCIN<81>"
$PN"BV71"3;
"VCCIN<82>"
$PN"BV69"3;
"VCCIN<83>"
$PN"BV67"3;
"VCCIN<84>"
$PN"BV65"3;
"VCCIN<85>"
$PN"BV63"3;
"VCCIN<86>"
$PN"BV61"3;
"VCCIN<87>"
$PN"BU84"3;
"VCCIN<88>"
$PN"BU82"3;
"VCCIN<89>"
$PN"BU80"3;
"VCCIN<90>"
$PN"BU78"3;
"VCCIN<91>"
$PN"BU76"3;
"VCCIN<92>"
$PN"BU74"3;
"VCCIN<93>"
$PN"BU72"3;
"VCCIN<94>"
$PN"BU70"3;
"VCCIN<95>"
$PN"BU68"3;
"VCCIN<96>"
$PN"BU66"3;
"VCCIN<97>"
$PN"BU64"3;
"VCCIN<98>"
$PN"BU62"3;
"VCCIN<99>"
$PN"BU60"3;
"VCCIN<100>"
$PN"BT83"3;
"VCCIN<101>"
$PN"BT81"3;
"VCCIN<102>"
$PN"BT79"3;
"VCCIN<103>"
$PN"BT77"3;
"VCCIN<104>"
$PN"BT75"3;
"VCCIN<105>"
$PN"BT73"3;
"VCCIN<106>"
$PN"BT71"3;
"VCCIN<107>"
$PN"BT69"3;
"VCCIN<108>"
$PN"BT67"3;
"VCCIN<109>"
$PN"BT65"3;
"VCCIN<110>"
$PN"BT63"3;
"VCCIN<111>"
$PN"BT61"3;
"VCCIN<112>"
$PN"BR84"3;
"VCCIN<113>"
$PN"BR62"3;
"VCCIN<114>"
$PN"BR60"3;
"VCCIN<115>"
$PN"BP83"3;
"VCCIN<116>"
$PN"BP81"3;
"VCCIN<117>"
$PN"BP79"3;
"VCCIN<118>"
$PN"BP77"3;
"VCCIN<119>"
$PN"BP75"3;
"VCCIN<120>"
$PN"BP73"3;
"VCCIN<121>"
$PN"BP71"3;
"VCCIN<122>"
$PN"BP69"3;
"VCCIN<123>"
$PN"BP67"3;
"VCCIN<124>"
$PN"BP65"3;
"VCCIN<125>"
$PN"BP63"3;
"VCCIN<126>"
$PN"BP61"3;
"VCCIN<127>"
$PN"BN84"3;
"VCCIN<128>"
$PN"BN82"3;
"VCCIN<129>"
$PN"BN80"3;
%"PVCCIO_CPU1"
"1","(-500,1500)","0","mstr_symbols","I52";
;
HDL_POWER"PVCCIO_CPU1"
CDS_LIB"mstr_symbols"
VOLTAGE"1.1V"
BODY_TYPE"PLUMBING";
"G\NAC"7;
%"RES"
"2","(-500,1200)","0","mstr_discrete","I53";
;
CDS_SEC"1"
CDS_LOCATION"R3D32"
SEC_TYPE"0402"
SEC"1"
ROOM"CPU1"
CDS_LIB"mstr_discrete"
PART_NUMBER"G21796-066"
LOCATION"R3D32"
VALUE"10.0"
MATERIAL"EMPTY"
PACK_TYPE"0402"
WATTAGE"1/16W"
TOLERANCE"1%";
"A"
$PN"1"7;
"B"
$PN"2"8;
END.
